G04 ================== begin FILE IDENTIFICATION RECORD ==================*
G04 Layout Name:  14629-1a.brd*
G04 Film Name:    L4*
G04 File Format:  Gerber RS274X*
G04 File Origin:  Cadence Allegro 16.5-S037*
G04 Origin Date:  Tue Nov 25 11:50:54 2014*
G04 *
G04 Layer:  VIA CLASS/BOTTOM*
G04 Layer:  PIN/BOTTOM*
G04 Layer:  ETCH/BOTTOM*
G04 Layer:  DRAWING FORMAT/LAYER_PCB_STORY*
G04 Layer:  DRAWING FORMAT/LAYER_L4*
G04 *
G04 Offset:    (0.00 0.00)*
G04 Mirror:    No*
G04 Mode:      Positive*
G04 Rotation:  0*
G04 FullContactRelief:  No*
G04 UndefLineWidth:     6.00*
G04 ================== end FILE IDENTIFICATION RECORD ====================*
%FSLAX35Y35*MOIN*%
%IR0*IPPOS*OFA0.00000B0.00000*MIA0B0*SFA1.00000B1.00000*%
%ADD10C,.01*%
%ADD12C,.04*%
%ADD20C,.052*%
%ADD16R,.197X.032*%
%ADD19C,.064*%
%ADD13C,.028*%
%ADD18C,.057*%
%ADD14R,.001X.001*%
%ADD17R,.248X.165*%
%ADD15R,.248X.372*%
%ADD11C,.355*%
%ADD21C,.02*%
%ADD22C,.03*%
%ADD23C,.006*%
%ADD24C,.0055*%
%ADD29C,.05204*%
%ADD26C,.08104*%
%ADD27C,.07604*%
%ADD28C,.08804*%
%ADD25C,.18204*%
G75*
%LPD*%
G75*
G36*
G01X4381Y3203D02*
X3479Y4105D01*
Y74479D01*
X3500Y74500D01*
Y78500D01*
X4000Y79000D01*
X38000D01*
X54564Y62436D01*
X547960D01*
X591500Y105976D01*
Y133348D01*
G02X592271Y133498I400J0D01*
G03X596664Y145062I8438J3411D01*
G02X596203Y145703I-178J358D01*
G01X610000Y159500D01*
Y196000D01*
X606500Y199500D01*
X590500D01*
X590325Y199675D01*
G02X590617Y200358I282J283D01*
G03X590443Y208452I93J4051D01*
G02X590134Y209134I-26J399D01*
G01X591419Y210419D01*
X591479Y210431D01*
G03X588832Y218000I-770J3978D01*
G01X582586D01*
G03X578832I-1877J-3591D01*
G01X572586D01*
G03X568874Y218022I-1877J-3591D01*
G01X568831Y218000D01*
X568500D01*
X566750Y216250D01*
Y215272D01*
X566746Y215252D01*
G03Y213566I3963J-843D01*
G01X566750Y213546D01*
Y211760D01*
X563851D01*
X553260Y222351D01*
Y278585D01*
X490976Y340869D01*
Y350057D01*
G03Y354343I-1476J2143D01*
G01Y373357D01*
G03X487766Y377440I-1476J2143D01*
G02X487234I-266J299D01*
G03X485372Y372901I-1734J-1940D01*
G02X485562Y372701I-10J-200D01*
G01Y342386D01*
G03X487412Y337668I1476J-2143D01*
G01X487512Y337682D01*
X548524Y276670D01*
Y220388D01*
X561888Y207024D01*
X566750D01*
Y205272D01*
X566746Y205252D01*
G03Y203566I3963J-843D01*
G01X566750Y203546D01*
Y200750D01*
X554000Y188000D01*
X417500D01*
X410564Y194936D01*
X-32902D01*
X-33302Y195336D01*
Y231336D01*
X-32702Y231936D01*
X-12538D01*
X-12366Y232108D01*
Y234653D01*
X-12575Y234862D01*
X-32628D01*
X-33202Y235436D01*
Y271336D01*
X-32609Y271929D01*
X-12610D01*
X-12463Y272076D01*
Y274708D01*
X-12616Y274861D01*
X-32727D01*
X-33202Y275336D01*
Y288394D01*
X-32557Y289039D01*
X890D01*
X3398Y291547D01*
Y297936D01*
X898Y300436D01*
X-3602D01*
X-4102Y300936D01*
Y302936D01*
X-3602Y303436D01*
X50398D01*
X60898Y313936D01*
Y372936D01*
X68398Y380436D01*
X497398D01*
X500398Y377436D01*
Y344436D01*
X535398Y309436D01*
X571898D01*
X574398Y311936D01*
Y319936D01*
X576398Y321936D01*
X612398D01*
X614898Y324436D01*
Y344436D01*
X613898Y345436D01*
X534398D01*
X528898Y350936D01*
Y382436D01*
X541898Y395436D01*
X613398D01*
X616398Y398436D01*
Y407436D01*
X617398Y408436D01*
X621898D01*
X622898Y409436D01*
Y416602D01*
X616064Y423436D01*
X562522D01*
G02X562269Y424146I0J400D01*
G03X556709I-2780J3413D01*
G02X556456Y423436I-253J-310D01*
G01X519998D01*
X504498Y407936D01*
X45834D01*
X26898Y389000D01*
Y360936D01*
X16898Y350936D01*
X3434D01*
X434Y353936D01*
X-9102D01*
X-10102Y354936D01*
Y361936D01*
X-9602Y362436D01*
X-3602D01*
X-3595Y362435D01*
G03X3398Y368936I475J6501D01*
G01Y467936D01*
X4898Y469436D01*
X635898D01*
X637256Y468078D01*
Y388044D01*
X628091Y381936D01*
X545898D01*
G03X538898Y374936I0J-7000D01*
G01Y357436D01*
G03X545898Y350436I7000J0D01*
G01X627981D01*
X637183Y344334D01*
Y321000D01*
X636183Y320000D01*
X621500D01*
X617500Y316000D01*
Y133000D01*
X621500Y129000D01*
X636000D01*
X637183Y127817D01*
Y3894D01*
X636492Y3203D01*
X4381D01*
G37*
G36*
G01X608000Y162000D02*
X589000Y143000D01*
Y106500D01*
X546936Y64436D01*
X56500D01*
X38936Y82000D01*
X5898D01*
X3398Y84500D01*
Y110436D01*
X-921Y114755D01*
X-30850D01*
X-30866Y114772D01*
X-32938D01*
X-33302Y115136D01*
Y151236D01*
X-32642Y151896D01*
X-12594D01*
X-12326Y152164D01*
Y154539D01*
X-12645Y154858D01*
X-33024D01*
X-33302Y155136D01*
Y191436D01*
X-32778Y191960D01*
X409000D01*
X415960Y185000D01*
X555500D01*
X567500Y197000D01*
X605500D01*
X608000Y194500D01*
Y162000D01*
G37*
G36*
G01X540398Y397436D02*
X526398Y383436D01*
Y350436D01*
X533898Y342936D01*
X609398D01*
X611148Y341186D01*
Y326186D01*
X609898Y324936D01*
X575398D01*
X571898Y321436D01*
Y313436D01*
X570898Y312436D01*
X536898D01*
X503398Y345936D01*
Y380936D01*
X501398Y382936D01*
X66898D01*
X58898Y374936D01*
Y315936D01*
X48563Y305601D01*
X-17483D01*
X-17499Y305617D01*
X-31020D01*
X-31265Y305862D01*
Y308534D01*
X-31081Y308718D01*
X-17690D01*
X-17556Y308852D01*
Y310554D01*
X-17647Y310645D01*
X-31106D01*
X-31265Y310804D01*
Y313269D01*
X-30873Y313661D01*
X-7228D01*
X-7218Y313660D01*
G03X-6662I278J2587D01*
G01X-6652Y313661D01*
X-1607D01*
X-427Y314841D01*
X4398D01*
X10743Y321186D01*
X34148D01*
X45398Y332436D01*
Y374436D01*
X36000Y383834D01*
Y387998D01*
X36800Y388798D01*
X36804D01*
X37002Y388996D01*
X40562D01*
X40566Y389000D01*
X42500D01*
X53436Y399936D01*
X510262D01*
X523962Y413636D01*
X613198D01*
X613898Y412936D01*
Y399436D01*
X611898Y397436D01*
X540398D01*
G37*
%LPC*%
G75*
G36*
G01X25118Y253002D02*
G02X32056Y246063I0J-6938D01*
G01Y226378D01*
G02X25118Y219440I-6938J0D01*
G01X21181D01*
G02X14242Y226378I0J6939D01*
G01Y246063D01*
G02X21181Y253002I6939J0D01*
G01X25118D01*
G37*
G36*
G01X557373Y234075D02*
X557473Y234061D01*
X564888Y241476D01*
X567048D01*
G03X567376Y242104I-1J400D01*
G02X574042I3333J2305D01*
G03X574370Y241476I329J-228D01*
G01X575688D01*
X576995Y242783D01*
X576946Y242906D01*
G02X579206Y240646I3763J1503D01*
G01X579083Y240695D01*
X577797Y239409D01*
X579083Y238123D01*
X579206Y238172D01*
G02X576946Y235912I1503J-3763D01*
G01X576995Y236035D01*
X576256Y236774D01*
X574704D01*
G03X574345Y236197I0J-400D01*
G02X567221Y236472I-3636J-1788D01*
G01X567249Y236519D01*
Y236774D01*
X566862D01*
X563614Y233526D01*
X563699Y233391D01*
G02X559738Y230085I-2199J-1391D01*
G03X559139Y230018I-270J-295D01*
G02X557373Y234075I-2139J1482D01*
G37*
G54D29*
X537136Y326402D03*
G54D26*
X570709Y276929D03*
X580709D03*
X570709Y266929D03*
X580709D03*
X570709Y256929D03*
X580709D03*
X570709Y224409D03*
X580709D03*
X570709Y286929D03*
X580709D03*
X600709Y214409D03*
Y204409D03*
X590709Y244409D03*
X600709D03*
X590709Y276929D03*
X600709D03*
X590709Y266929D03*
X600709D03*
X590709Y256929D03*
X600709D03*
X590709Y234409D03*
X600709D03*
X590709Y224409D03*
X600709D03*
X590709Y286929D03*
X600709D03*
X570709Y161889D03*
X580709D03*
X570709Y191889D03*
X580709D03*
X570709Y181889D03*
X580709D03*
X570709Y171889D03*
X580709D03*
X590709Y161889D03*
X600709D03*
X590709Y191889D03*
X600709D03*
X590709Y181889D03*
X600709D03*
X590709Y171889D03*
X600709D03*
G54D27*
X571496Y433071D03*
X581339D03*
X591182D03*
G54D28*
X603780Y442126D03*
G54D25*
X600709Y311909D03*
%LPD*%
G75*
G54D10*
X-23621Y15748D03*
Y937008D03*
X600709Y136909D03*
Y311909D03*
X1312285Y15747D03*
X1312281Y889328D03*
G54D11*
X30157Y61023D03*
Y415354D03*
X498661Y23622D03*
X518346Y448818D03*
G54D20*
X571496Y433071D03*
X581339D03*
X591182D03*
G54D21*
G01X-4246Y-109426D02*
Y-189426D01*
G01D02*
X1290354D01*
G01X-4246Y-144926D02*
X1290354D01*
G01X-8246Y-93426D02*
G02I-12000J0D01*
G01X-13396D02*
G02I-6850J0D01*
G01X-20246Y-109426D02*
Y-77426D01*
G01X-4246Y-93426D02*
X-36246D01*
G01X-4246Y-109426D02*
X1290354D01*
G01X502854D02*
Y-189426D01*
G01X570709Y157637D02*
Y161889D01*
G01D02*
X574961D01*
G01X566457D02*
X570709D01*
G01D02*
Y166141D01*
G01X576457Y161889D02*
X580709D01*
G01X570709Y191889D02*
X574961D01*
G01X566457D02*
X570709D01*
G01D02*
Y196141D01*
G01Y187637D02*
Y191889D01*
G01X576457D02*
X580709D01*
G01X570709Y181889D02*
X574961D01*
G01X566457D02*
X570709D01*
G01D02*
Y186141D01*
G01Y177637D02*
Y181889D01*
G01X576457D02*
X580709D01*
G01X570709Y171889D02*
X574961D01*
G01X566457D02*
X570709D01*
G01D02*
Y176141D01*
G01Y167637D02*
Y171889D01*
G01X576457D02*
X580709D01*
G01X570709Y272677D02*
Y276929D01*
G01Y266929D02*
X574961D01*
G01X566457D02*
X570709D01*
G01D02*
Y271181D01*
G01Y262677D02*
Y266929D01*
G01X576457D02*
X580709D01*
G01X570709Y256929D02*
X574961D01*
G01X566457D02*
X570709D01*
G01D02*
Y261181D01*
G01Y252677D02*
Y256929D01*
G01X576457D02*
X580709D01*
G01X570709Y276929D02*
X574961D01*
G01X566457D02*
X570709D01*
G01D02*
Y281181D01*
G01X576457Y276929D02*
X580709D01*
G01X570709Y286929D02*
X574961D01*
G01X566457D02*
X570709D01*
G01D02*
Y291181D01*
G01Y282677D02*
Y286929D01*
G01X576457D02*
X580709D01*
G01X559489Y427559D02*
X564091D01*
G01X554887D02*
X559489D01*
G01D02*
Y432161D01*
G01X580709Y157637D02*
Y161889D01*
G01X590709Y157637D02*
Y161889D01*
G01X600709Y157637D02*
Y161889D01*
G01X580709D02*
X584961D01*
G01X580709D02*
Y166141D01*
G01Y191889D02*
X584961D01*
G01X580709D02*
Y196141D01*
G01Y187637D02*
Y191889D01*
G01Y181889D02*
X584961D01*
G01X580709D02*
Y186141D01*
G01Y177637D02*
Y181889D01*
G01Y171889D02*
X584961D01*
G01X580709D02*
Y176141D01*
G01Y167637D02*
Y171889D01*
G01X590709Y161889D02*
X594961D01*
G01X586457D02*
X590709D01*
G01D02*
Y166141D01*
G01X600709Y161889D02*
X604961D01*
G01X596457D02*
X600709D01*
G01D02*
Y166141D01*
G01X590709Y191889D02*
X594961D01*
G01X586457D02*
X590709D01*
G01D02*
Y196141D01*
G01Y187637D02*
Y191889D01*
G01X600709D02*
X604961D01*
G01X596457D02*
X600709D01*
G01D02*
Y196141D01*
G01Y187637D02*
Y191889D01*
G01X590709Y181889D02*
X594961D01*
G01X586457D02*
X590709D01*
G01D02*
Y186141D01*
G01Y177637D02*
Y181889D01*
G01X600709D02*
X604961D01*
G01X596457D02*
X600709D01*
G01D02*
Y186141D01*
G01Y177637D02*
Y181889D01*
G01X590709Y171889D02*
X594961D01*
G01X586457D02*
X590709D01*
G01D02*
Y176141D01*
G01Y167637D02*
Y171889D01*
G01X600709D02*
X604961D01*
G01X596457D02*
X600709D01*
G01D02*
Y176141D01*
G01Y167637D02*
Y171889D01*
G01Y214409D02*
X604961D01*
G01X596457D02*
X600709D01*
G01D02*
Y218661D01*
G01Y210157D02*
Y214409D01*
G01X590709Y204409D02*
X594961D01*
G01X590709D02*
Y208661D01*
G01Y200157D02*
Y204409D01*
G01X580709Y272677D02*
Y276929D01*
G01Y266929D02*
X584961D01*
G01X580709D02*
Y271181D01*
G01Y262677D02*
Y266929D01*
G01Y256929D02*
X584961D01*
G01X580709D02*
Y261181D01*
G01Y252677D02*
Y256929D01*
G01X590709Y244409D02*
X594961D01*
G01X586457D02*
X590709D01*
G01D02*
Y248661D01*
G01Y240157D02*
Y244409D01*
G01Y272677D02*
Y276929D01*
G01X600709Y272677D02*
Y276929D01*
G01X590709Y266929D02*
X594961D01*
G01X586457D02*
X590709D01*
G01D02*
Y271181D01*
G01Y262677D02*
Y266929D01*
G01X600709D02*
X604961D01*
G01X596457D02*
X600709D01*
G01D02*
Y271181D01*
G01Y262677D02*
Y266929D01*
G01X590709Y256929D02*
X594961D01*
G01X586457D02*
X590709D01*
G01D02*
Y261181D01*
G01Y252677D02*
Y256929D01*
G01X600709D02*
X604961D01*
G01X596457D02*
X600709D01*
G01D02*
Y261181D01*
G01Y252677D02*
Y256929D01*
G01Y234409D02*
X604961D01*
G01X596457D02*
X600709D01*
G01D02*
Y238661D01*
G01Y230157D02*
Y234409D01*
G01X590709Y224409D02*
X594961D01*
G01X586457D02*
X590709D01*
G01D02*
Y228661D01*
G01Y220157D02*
Y224409D01*
G01X580709Y276929D02*
X584961D01*
G01X580709D02*
Y281181D01*
G01Y286929D02*
X584961D01*
G01X580709D02*
Y291181D01*
G01Y282677D02*
Y286929D01*
G01X590709Y276929D02*
X594961D01*
G01X586457D02*
X590709D01*
G01D02*
Y281181D01*
G01X600709Y276929D02*
X604961D01*
G01X596457D02*
X600709D01*
G01D02*
Y281181D01*
G01X590709Y286929D02*
X594961D01*
G01X586457D02*
X590709D01*
G01D02*
Y291181D01*
G01Y282677D02*
Y286929D01*
G01X600709D02*
X604961D01*
G01X596457D02*
X600709D01*
G01D02*
Y291181D01*
G01Y282677D02*
Y286929D01*
G01X603780Y442126D02*
X608382D01*
G01X599178D02*
X603780D01*
G01D02*
Y446728D01*
G01Y437524D02*
Y442126D01*
G01X640354Y-109426D02*
Y-189426D01*
G01X755354Y-109426D02*
Y-189426D01*
G01X922854Y-109426D02*
Y-189426D01*
G01X1092854Y-109426D02*
Y-189426D01*
G01X1290354Y-109426D02*
Y-189426D01*
G01X1318354Y-93426D02*
G02I-12000J0D01*
G01X1313204D02*
G02I-6850J0D01*
G01X1306354Y-109426D02*
Y-77426D01*
G01X1322354Y-93426D02*
X1290354D01*
G54D12*
G01X2334Y318654D02*
X9116Y325436D01*
X20898D01*
G01X536398Y418936D02*
X522898D01*
X508398Y404436D01*
X51476D01*
X51472Y404434D01*
X39236Y392198D01*
X35676D01*
X35478Y392000D01*
X35474D01*
X32000Y388526D01*
Y382000D01*
X41398Y372602D01*
Y335436D01*
X31398Y325436D01*
X20898D01*
G01X617798Y413000D02*
Y415012D01*
X613874Y418936D01*
X536398D01*
X-23622Y62794D03*
Y916269D03*
X1297695Y58466D03*
G54D22*
G01X-26055Y302202D02*
X-2948D01*
G01X-26055Y337202D02*
X-7102D01*
G01X-26055Y347202D02*
X-6602D01*
G01Y357202D02*
X-26055D01*
G54D13*
X6419Y116482D03*
X-3350Y117504D03*
X6419Y126482D03*
X-3581D03*
X6419Y136482D03*
X-3581D03*
X6419Y146482D03*
X-3581D03*
X6419Y156482D03*
X-3581D03*
X-2602Y206936D03*
X7398D03*
X-2602Y216936D03*
X7398D03*
X6419Y166482D03*
X-3581D03*
Y176482D03*
X6419D03*
X-2602Y226936D03*
X7398D03*
X-2602Y246936D03*
X7398D03*
X-2602Y236936D03*
X7398D03*
Y256936D03*
X-2602D03*
Y266936D03*
X7398D03*
Y276936D03*
X-2602D03*
X7398Y286936D03*
X3398Y326936D03*
X-2948Y302202D03*
X-2602Y316436D03*
X-7102Y327202D03*
X-6940Y316247D03*
X2334Y318654D03*
X1494Y343705D03*
X5694D03*
X-6602Y347202D03*
X-7102Y337202D03*
X-6602Y357202D03*
X6898Y387436D03*
X6398Y369936D03*
X-2722Y341000D03*
X1635Y347764D03*
X6898Y445436D03*
Y465436D03*
X16419Y6482D03*
Y26482D03*
X36419Y6482D03*
Y26482D03*
X56419Y46482D03*
X16419Y86482D03*
X36419D03*
X56419Y66482D03*
Y86482D03*
X26419Y116482D03*
X16419D03*
X26419Y126482D03*
X16419D03*
X26419Y136482D03*
X16419D03*
X26419Y146482D03*
X16419D03*
X26419Y156482D03*
X16419D03*
X36419Y126482D03*
X16419Y106482D03*
X36419D03*
Y146482D03*
X56419Y126482D03*
Y106482D03*
Y146482D03*
X46898Y152936D03*
Y117936D03*
X27398Y206936D03*
X17398D03*
X27398Y216936D03*
X17398D03*
X26419Y186482D03*
X16419D03*
X26419Y166482D03*
X16419D03*
Y176482D03*
X26419D03*
X36419Y186482D03*
Y166482D03*
X56419Y186482D03*
Y166482D03*
X57398Y206936D03*
X37398D03*
X47398Y214936D03*
X46898Y182936D03*
X17398Y256936D03*
X27398D03*
Y266936D03*
X17398D03*
X57398Y226936D03*
X36769D03*
X57398Y246936D03*
Y266936D03*
X36769Y246936D03*
X37398Y266936D03*
X48398Y274936D03*
X17398Y276936D03*
X27398Y286936D03*
X17398D03*
X27398Y276936D03*
X10000Y332000D03*
X57398Y286936D03*
X37398D03*
X64398Y304436D03*
X26500Y330436D03*
X20898Y325436D03*
X49398Y326436D03*
X20398Y309936D03*
X30923Y335665D03*
X25500Y353000D03*
X25000Y343000D03*
X33986Y362933D03*
X26723Y335665D03*
X22000Y374500D03*
X34898Y344936D03*
X57398Y348682D03*
X52705Y348626D03*
X48325Y348514D03*
X62398Y338436D03*
X37500Y386500D03*
X22000Y387500D03*
X61898Y358936D03*
X14000Y336000D03*
X53398Y388936D03*
X62000Y442500D03*
X60052Y394674D03*
X35830Y442464D03*
X55352Y394674D03*
X51094Y394478D03*
X55500Y417000D03*
X19898Y465436D03*
X39898D03*
X76419Y46482D03*
X116419D03*
X96419D03*
X76000Y32000D03*
X76419Y66482D03*
Y86482D03*
X116419Y66482D03*
X96419D03*
X116419Y86482D03*
X96419D03*
X73000Y94500D03*
X76419Y126482D03*
Y106482D03*
Y146482D03*
X116419Y126482D03*
Y106482D03*
X96419Y126482D03*
Y106482D03*
X116419Y146482D03*
X96419D03*
X76419Y186482D03*
Y166482D03*
X77398Y206936D03*
X116419Y186482D03*
Y166482D03*
X96419Y186482D03*
Y166482D03*
X117398Y206936D03*
X97398D03*
X77398Y226936D03*
Y246936D03*
Y266936D03*
X117398Y226936D03*
X97398D03*
X117398Y246936D03*
X97398D03*
Y266936D03*
X116398D03*
X77398Y286936D03*
X86398Y303936D03*
X97398Y286936D03*
X116398D03*
X114398Y308936D03*
X77898Y338436D03*
X78398Y358436D03*
X115330Y337964D03*
X96398Y337936D03*
X115330Y377964D03*
Y357964D03*
X95330Y377964D03*
Y357964D03*
X78398Y371936D03*
X105330Y442964D03*
X85330D03*
X75500Y417500D03*
X115330Y417964D03*
X95330D03*
X67398Y416936D03*
X91500Y465500D03*
X117500D03*
X67830Y465464D03*
X136419Y6482D03*
Y46482D03*
X176419Y6482D03*
Y26482D03*
X156419Y6482D03*
Y26482D03*
X176419Y46482D03*
X156419D03*
X136419Y66482D03*
Y86482D03*
X176419Y66482D03*
X156419D03*
X176419Y86482D03*
X156419D03*
X136419Y126482D03*
Y106482D03*
Y146482D03*
X176419Y126482D03*
Y106482D03*
X156419Y126482D03*
Y106482D03*
X176419Y146482D03*
X156419D03*
X136419Y186482D03*
Y166482D03*
X137398Y206936D03*
X176419Y186482D03*
Y166482D03*
X156419Y186482D03*
Y166482D03*
X177398Y206436D03*
X157398Y206936D03*
X137398Y226936D03*
Y246936D03*
Y266936D03*
X177398Y226936D03*
X157398D03*
X177398Y246936D03*
Y266936D03*
X157398Y246936D03*
Y266936D03*
X137398Y286936D03*
X177398D03*
X157398D03*
X135330Y337964D03*
Y377964D03*
Y357964D03*
X175330Y337964D03*
X155330D03*
X175330Y377964D03*
Y357964D03*
X155330Y377964D03*
Y357964D03*
X132000Y442500D03*
X135330Y417964D03*
X175500Y442000D03*
X175330Y417964D03*
X155000Y442000D03*
X155330Y417964D03*
X139898Y465436D03*
X159898D03*
X196419Y6482D03*
Y26482D03*
Y46482D03*
X236419Y6482D03*
Y26482D03*
X216419Y6482D03*
Y26482D03*
X236419Y46482D03*
X216419D03*
X196419Y66482D03*
Y86482D03*
X236419Y66482D03*
X216419D03*
X236419Y86482D03*
X216419D03*
X196419Y126482D03*
Y106482D03*
Y146482D03*
X236419Y126482D03*
Y106482D03*
X216419Y126482D03*
Y106482D03*
X236419Y146482D03*
X216419D03*
X189398Y115936D03*
X196419Y186482D03*
Y166482D03*
X197398Y206436D03*
X236419Y186482D03*
Y166482D03*
X216419Y186482D03*
Y166482D03*
X217398Y206436D03*
X197398Y226936D03*
Y246936D03*
Y266936D03*
X217398Y226936D03*
Y246936D03*
Y266936D03*
X197398Y286936D03*
X217398D03*
X195330Y337964D03*
Y377964D03*
Y357964D03*
X235330Y337964D03*
X215330D03*
X235330Y377964D03*
Y357964D03*
X215330Y377964D03*
Y357964D03*
X196000Y442500D03*
X195330Y417964D03*
X235830Y442464D03*
X235330Y417964D03*
X215830Y442464D03*
X215330Y417964D03*
X208398Y433436D03*
X179898Y465436D03*
X219898D03*
X199898D03*
X256419Y6482D03*
Y26482D03*
X276419Y6482D03*
Y26482D03*
X256419Y46482D03*
X276419D03*
X248898Y35936D03*
X256419Y66482D03*
X273500Y66500D03*
X256419Y86482D03*
X274500Y86500D03*
X256419Y126482D03*
X276419D03*
X256419Y106482D03*
X274500Y106500D03*
X256419Y146482D03*
X276419D03*
X237398Y206436D03*
X256419Y186482D03*
X275500Y186500D03*
X251500Y166500D03*
X276419Y166482D03*
X257398Y206436D03*
X277398D03*
X237398Y226936D03*
Y246936D03*
Y266936D03*
X257398Y226936D03*
X277398D03*
X257398Y246936D03*
X277398D03*
X257398Y266936D03*
X277398D03*
X247898Y234936D03*
X237398Y286936D03*
X257398D03*
X279398D03*
X282398Y312436D03*
X255330Y337964D03*
X275330D03*
X255330Y377964D03*
X275330D03*
X255330Y357964D03*
X275330D03*
X255830Y442464D03*
X275830D03*
X255330Y417964D03*
X275330D03*
X239898Y465436D03*
X279898D03*
X259898D03*
X296419Y6482D03*
Y26482D03*
Y46482D03*
X316419Y6482D03*
Y26482D03*
X336419Y6482D03*
Y26482D03*
X316419Y46482D03*
X336419D03*
X302000Y67000D03*
X301000Y86500D03*
X316419Y66482D03*
X336419D03*
X316419Y86482D03*
X336419D03*
X296419Y126482D03*
X300000Y106500D03*
X296419Y146482D03*
X316419Y126482D03*
X336419D03*
X316419Y106482D03*
X336419D03*
X316419Y146482D03*
X336419D03*
X347898Y117436D03*
X296419Y186482D03*
X295500Y169000D03*
X297398Y206436D03*
X317500Y186500D03*
X336419Y186482D03*
X317000Y166500D03*
X338500Y166000D03*
X317398Y206436D03*
X337398D03*
X297398Y226936D03*
Y246936D03*
Y266936D03*
X317398Y226936D03*
X337398D03*
X317398Y246936D03*
X337398D03*
X317398Y266936D03*
X337398D03*
X300398Y286936D03*
X317398D03*
X337398D03*
X295330Y337964D03*
Y377964D03*
Y357964D03*
X315330Y337964D03*
X335330D03*
X315330Y377964D03*
X335330D03*
X315330Y357964D03*
X335330D03*
X295830Y442464D03*
X295330Y417964D03*
X315830Y442464D03*
X335830D03*
X315330Y417964D03*
X335330D03*
X299898Y465436D03*
X339898D03*
X319898D03*
X356419Y6482D03*
Y26482D03*
Y46482D03*
X376419Y6482D03*
Y26482D03*
X396419Y6482D03*
Y26482D03*
X376419Y46482D03*
X396419D03*
X365398Y35936D03*
X356419Y66482D03*
Y86482D03*
X376419Y66482D03*
X396419D03*
X376419Y86482D03*
X396419D03*
X356419Y126482D03*
Y106482D03*
Y146482D03*
X376419Y126482D03*
X396419D03*
X376419Y106482D03*
X396419D03*
X376419Y146482D03*
X396419D03*
X357500Y186500D03*
X354500Y166500D03*
X357398Y206436D03*
X376419Y186482D03*
X396419D03*
X380000Y166500D03*
X396419Y166482D03*
X377398Y206436D03*
X397398D03*
X357398Y226936D03*
Y246936D03*
Y266936D03*
X377398Y226936D03*
X397398D03*
X377398Y246936D03*
X397398D03*
X377398Y266936D03*
X397398D03*
X393241Y239988D03*
X357398Y286936D03*
X377398D03*
X397398D03*
X394022Y308262D03*
X355330Y337964D03*
Y377964D03*
Y357964D03*
X375330Y337964D03*
X395330D03*
X375330Y377964D03*
X395330D03*
X375330Y357964D03*
X395330D03*
X355830Y442464D03*
X355330Y417964D03*
X375830Y442464D03*
X395830D03*
X375330Y417964D03*
X395330D03*
X364398Y430936D03*
X399898Y465436D03*
X379898D03*
X359898D03*
X416419Y6482D03*
Y26482D03*
X436419Y6482D03*
X416419Y46482D03*
X436419D03*
X456419D03*
X416419Y66482D03*
X436419D03*
X456419D03*
X416419Y86482D03*
X436419D03*
X456419D03*
X416419Y126482D03*
X436419D03*
X456419D03*
X416419Y106482D03*
X436419D03*
X456419D03*
X416419Y146482D03*
X436419D03*
X456419D03*
X416500Y166000D03*
X417519Y174482D03*
Y170282D03*
X425919D03*
X421719D03*
Y174482D03*
X431100Y174500D03*
Y170300D03*
X439500D03*
Y174500D03*
X435300Y170300D03*
Y174500D03*
X444100D03*
Y170300D03*
X452500D03*
Y174500D03*
X448300Y170300D03*
Y174500D03*
X457100Y175000D03*
Y170800D03*
X461300D03*
Y175000D03*
X418300Y197500D03*
Y201700D03*
X422500D03*
X426700D03*
X422500Y197500D03*
X426700D03*
X431300D03*
Y201700D03*
X435500D03*
X439700D03*
X435500Y197500D03*
X439700D03*
X444800D03*
Y201700D03*
X449000D03*
X453200D03*
X449000Y197500D03*
X453200D03*
X457800D03*
Y201700D03*
X462000D03*
Y197500D03*
X425919Y174482D03*
X436500Y166000D03*
X456500Y166500D03*
X417398Y206436D03*
X437398D03*
X457398D03*
X417398Y226936D03*
X437398D03*
X457398D03*
X417398Y246936D03*
X437398D03*
X457398D03*
X437398Y266936D03*
X457398D03*
X418398D03*
X437398Y286936D03*
X457398D03*
X418398D03*
X415330Y337964D03*
X435398Y338436D03*
X455398D03*
X415330Y377964D03*
Y357964D03*
X435398Y358436D03*
Y378436D03*
X455398Y358436D03*
Y378436D03*
X435830Y442464D03*
X435330Y417964D03*
X455330D03*
X415830Y442464D03*
X415330Y417964D03*
X444500Y445000D03*
X454500Y465500D03*
X439898Y465436D03*
X419898D03*
X516419Y6482D03*
X476419Y46482D03*
X496419D03*
X516419D03*
Y66482D03*
X476419D03*
X496419D03*
X516419Y86482D03*
X496419D03*
X476419D03*
Y126482D03*
X516419D03*
X496419D03*
X516419Y106482D03*
X496419D03*
X476419D03*
X485443Y160670D03*
X481243D03*
X493843D03*
X489643D03*
X476419Y146482D03*
X516419D03*
X496419D03*
X519221Y160912D03*
X510821D03*
X506621D03*
X515021D03*
X465500Y170800D03*
Y175000D03*
X466200Y201700D03*
Y197500D03*
X485443Y164870D03*
X481243D03*
X493843D03*
X489643D03*
X477284Y174586D03*
X473084D03*
Y170386D03*
X477284D03*
X498395Y174685D03*
Y170485D03*
X492911Y206602D03*
X488711D03*
X492911Y210802D03*
X488711D03*
X484511D03*
Y206602D03*
X480311Y210802D03*
Y206602D03*
X498052Y200389D03*
Y196189D03*
X477087Y201172D03*
X472887D03*
X477087Y196972D03*
X472887D03*
X519221Y165112D03*
X510821D03*
X506621D03*
X515021D03*
X502595Y174685D03*
Y170485D03*
X506135Y210557D03*
X510335D03*
X514535D03*
X518735D03*
X506135Y206357D03*
X510335D03*
X514535D03*
X518735D03*
X502252Y200389D03*
Y196189D03*
X507398Y196436D03*
X497398Y226936D03*
X477398D03*
X520898Y228436D03*
X497398Y246936D03*
X477398D03*
Y266936D03*
X512500Y323000D03*
X492000Y321000D03*
X506500Y305500D03*
X520500Y331000D03*
X520381Y300757D03*
X489500Y375500D03*
X485500D03*
X495398Y338436D03*
X475398D03*
X495398Y358436D03*
Y378436D03*
X475398Y358436D03*
Y378436D03*
X489500Y352200D03*
X487039Y340243D03*
X477500Y370500D03*
X477000Y418000D03*
X499000Y418500D03*
X466500Y428000D03*
X506500Y418500D03*
X533619Y6482D03*
Y26482D03*
Y46482D03*
X550819Y6482D03*
Y26482D03*
Y46482D03*
X568019Y6482D03*
Y26482D03*
Y46482D03*
X525898Y33436D03*
X573623Y66967D03*
X536419Y66482D03*
X556419D03*
X536419Y86482D03*
X556419D03*
X568691Y66413D03*
X576419Y106482D03*
Y126482D03*
X536419D03*
X556419D03*
X536419Y106482D03*
X556419D03*
X544476Y161322D03*
X531876D03*
X536076D03*
X540276D03*
X536419Y146482D03*
X556419D03*
X526398Y116936D03*
X544477Y210389D03*
X544476Y165522D03*
X536076D03*
X531876D03*
X540276D03*
X552924Y175124D03*
X548724D03*
Y170924D03*
X552924D03*
X527711Y175174D03*
X523511D03*
Y170974D03*
X527711D03*
X531877Y210389D03*
X536077D03*
X540277D03*
X531877Y206189D03*
X536077D03*
X540277D03*
X544477D03*
X527761Y200632D03*
X523561D03*
X527761Y196432D03*
X523561D03*
X553171Y200877D03*
X548971D03*
X553171Y196677D03*
X548971D03*
X543000Y197500D03*
X546600Y257971D03*
X540898Y228436D03*
X561500Y232000D03*
X557000Y231500D03*
X560500Y268000D03*
X534898Y261436D03*
X549500Y305500D03*
X543900Y314000D03*
X559996Y282972D03*
X561500Y298000D03*
X534000Y282000D03*
X537136Y326402D03*
X525161Y311000D03*
X577500Y305000D03*
X548000Y442500D03*
X553000Y425000D03*
X536398Y418936D03*
X568500Y464841D03*
X538000D03*
X634119Y26482D03*
X585219Y46482D03*
Y26482D03*
Y6482D03*
X602419Y26482D03*
Y6482D03*
X619619D03*
Y26482D03*
Y46482D03*
X634119D03*
Y6482D03*
X602419Y46482D03*
X628500Y104000D03*
X626500Y78500D03*
X611253Y65701D03*
X584543Y86671D03*
X611398Y86936D03*
X633753Y65701D03*
X633898Y86936D03*
X634000Y123500D03*
X607000D03*
X616000Y138000D03*
Y115500D03*
X594500Y117000D03*
X616000Y173500D03*
X615500Y199000D03*
X615898Y244436D03*
Y224436D03*
X615398Y266436D03*
X587500Y318500D03*
X600000Y298500D03*
X616498Y316236D03*
X615398Y284436D03*
X633398Y325436D03*
X630000Y345500D03*
X600000Y337500D03*
Y342000D03*
X595500D03*
Y337500D03*
X630000Y387500D03*
X579500Y333500D03*
X612798Y413000D03*
X610898Y425436D03*
Y445436D03*
X617798Y413000D03*
X632898Y404936D03*
Y444936D03*
Y424936D03*
X605398Y409436D03*
X592000Y464841D03*
X610898Y465436D03*
X632898Y464936D03*
G54D23*
G01X121969Y-179426D02*
Y-161926D01*
G01X131139D02*
Y-179426D01*
G01Y-170676D02*
X121969D01*
G01X144054Y-179426D02*
X142744Y-179134D01*
X141434Y-177968D01*
X140560Y-175926D01*
X140124Y-173593D01*
X140560Y-171259D01*
X141434Y-169218D01*
X142744Y-168051D01*
X144054Y-167760D01*
X145364Y-168051D01*
X146674Y-169218D01*
X147547Y-171259D01*
X147766Y-173593D01*
X147547Y-175926D01*
X146674Y-177968D01*
X145364Y-179134D01*
X144054Y-179426D01*
G01X157842D02*
Y-167760D01*
G01Y-170676D02*
X158716Y-169218D01*
X160026Y-168051D01*
X161772Y-167760D01*
X163300Y-168051D01*
X164611Y-169218D01*
X165266Y-171259D01*
Y-179426D01*
G01X175779Y-171551D02*
X182766D01*
X182111Y-169509D01*
X181019Y-168343D01*
X179491Y-167760D01*
X177962Y-168051D01*
X176652Y-168926D01*
X175779Y-170968D01*
X175342Y-172718D01*
Y-174468D01*
X175779Y-176218D01*
X176871Y-177968D01*
X178181Y-179134D01*
X179709Y-179426D01*
X181237Y-178843D01*
X182766Y-177093D01*
G01X191969Y-184676D02*
X193279Y-185259D01*
X195026Y-184676D01*
X196117Y-183510D01*
X196991Y-182051D01*
X198300Y-177385D01*
X201139Y-167760D01*
G01X194152D02*
X198300Y-177385D01*
G01X233300Y-170093D02*
X234174Y-169218D01*
X234829Y-167760D01*
X235266Y-165717D01*
X234829Y-163968D01*
X233956Y-162801D01*
X232427Y-161926D01*
X226532D01*
Y-179426D01*
X233737D01*
X235266Y-178260D01*
X236139Y-176509D01*
X236576Y-174468D01*
X236139Y-172426D01*
X234829Y-170676D01*
X233300Y-170093D01*
X226532D01*
G01X252984Y-179426D02*
Y-167760D01*
G01Y-169801D02*
X252111Y-168635D01*
X250800Y-168051D01*
X249272Y-167760D01*
X247744Y-168343D01*
X246434Y-169509D01*
X245560Y-171259D01*
X245124Y-173593D01*
X245560Y-175926D01*
X246434Y-177676D01*
X247744Y-178843D01*
X249272Y-179426D01*
X250800Y-179134D01*
X252111Y-178260D01*
X252984Y-177093D01*
G01X270484Y-161926D02*
Y-179426D01*
G01Y-176802D02*
X269611Y-178260D01*
X268300Y-179134D01*
X266772Y-179426D01*
X265026Y-178843D01*
X263716Y-177385D01*
X262842Y-175635D01*
X262624Y-173593D01*
X262842Y-171551D01*
X263716Y-169801D01*
X265026Y-168343D01*
X266772Y-167760D01*
X268300Y-168051D01*
X269392Y-168635D01*
X270484Y-169801D01*
G01X280997Y-183801D02*
X282526Y-184968D01*
X284272Y-185259D01*
X285800Y-184968D01*
X287111Y-183510D01*
X287984Y-181468D01*
Y-167760D01*
G01Y-170093D02*
X287111Y-168926D01*
X285800Y-168051D01*
X284272Y-167760D01*
X282526Y-168343D01*
X281434Y-169509D01*
X280560Y-171551D01*
X280124Y-173593D01*
X280342Y-175343D01*
X281216Y-177385D01*
X282526Y-178843D01*
X284272Y-179426D01*
X285582Y-179134D01*
X287111Y-177968D01*
X287984Y-176802D01*
G01X298279Y-171551D02*
X305266D01*
X304611Y-169509D01*
X303519Y-168343D01*
X301991Y-167760D01*
X300462Y-168051D01*
X299152Y-168926D01*
X298279Y-170968D01*
X297842Y-172718D01*
Y-174468D01*
X298279Y-176218D01*
X299371Y-177968D01*
X300681Y-179134D01*
X302209Y-179426D01*
X303737Y-178843D01*
X305266Y-177093D01*
G01X315997Y-179426D02*
Y-167760D01*
G01Y-170093D02*
X317089Y-168926D01*
X318181Y-168051D01*
X319709Y-167760D01*
X320800Y-168051D01*
X322111Y-168926D01*
G01X349687Y-179426D02*
Y-161926D01*
X354927D01*
X356674Y-162801D01*
X357984Y-164843D01*
X358421Y-167176D01*
X357984Y-169509D01*
X356892Y-171259D01*
X354927Y-172135D01*
X349687D01*
G01X371554Y-161926D02*
Y-179426D01*
G01X366532Y-161926D02*
X376576D01*
G01X390800Y-170093D02*
X391674Y-169218D01*
X392329Y-167760D01*
X392766Y-165717D01*
X392329Y-163968D01*
X391456Y-162801D01*
X389927Y-161926D01*
X384032D01*
Y-179426D01*
X391237D01*
X392766Y-178260D01*
X393639Y-176509D01*
X394076Y-174468D01*
X393639Y-172426D01*
X392329Y-170676D01*
X390800Y-170093D01*
X384032D01*
G01X208377Y-134426D02*
Y-116926D01*
X214054Y-131509D01*
X219731Y-116926D01*
Y-134426D01*
G01X231554D02*
X230244Y-134134D01*
X228934Y-132968D01*
X228060Y-130926D01*
X227624Y-128593D01*
X228060Y-126259D01*
X228934Y-124218D01*
X230244Y-123051D01*
X231554Y-122760D01*
X232864Y-123051D01*
X234174Y-124218D01*
X235047Y-126259D01*
X235266Y-128593D01*
X235047Y-130926D01*
X234174Y-132968D01*
X232864Y-134134D01*
X231554Y-134426D01*
G01X252984Y-116926D02*
Y-134426D01*
G01Y-131802D02*
X252111Y-133260D01*
X250800Y-134134D01*
X249272Y-134426D01*
X247526Y-133843D01*
X246216Y-132385D01*
X245342Y-130635D01*
X245124Y-128593D01*
X245342Y-126551D01*
X246216Y-124801D01*
X247526Y-123343D01*
X249272Y-122760D01*
X250800Y-123051D01*
X251892Y-123635D01*
X252984Y-124801D01*
G01X263279Y-126551D02*
X270266D01*
X269611Y-124509D01*
X268519Y-123343D01*
X266991Y-122760D01*
X265462Y-123051D01*
X264152Y-123926D01*
X263279Y-125968D01*
X262842Y-127718D01*
Y-129468D01*
X263279Y-131218D01*
X264371Y-132968D01*
X265681Y-134134D01*
X267209Y-134426D01*
X268737Y-133843D01*
X270266Y-132093D01*
G01X284054Y-134426D02*
Y-116926D01*
G01X536554Y-179426D02*
Y-161926D01*
X533934Y-165426D01*
G01Y-179426D02*
X539174D01*
G01X556674D02*
Y-161926D01*
X548595Y-174468D01*
X559513D01*
G01X567406Y-172135D02*
X568934Y-170093D01*
X570244Y-168926D01*
X571991Y-168343D01*
X573519Y-168926D01*
X574611Y-170093D01*
X575484Y-171843D01*
X575702Y-173884D01*
X575484Y-175635D01*
X574611Y-177385D01*
X573300Y-178843D01*
X571772Y-179426D01*
X570026Y-178843D01*
X568497Y-177093D01*
X567624Y-174468D01*
X567406Y-171551D01*
X567842Y-167760D01*
X568497Y-165717D01*
X569589Y-163676D01*
X571117Y-162218D01*
X572646Y-161926D01*
X574174Y-162509D01*
X575266Y-163968D01*
G01X584906Y-164843D02*
X586216Y-163093D01*
X587744Y-162218D01*
X589491Y-161926D01*
X591674Y-162509D01*
X593202Y-163968D01*
X593639Y-165717D01*
X593421Y-167468D01*
X592547Y-168926D01*
X588181Y-171843D01*
X586216Y-173884D01*
X584906Y-176802D01*
X584469Y-179426D01*
X593639D01*
G01X602842Y-177385D02*
X604371Y-178843D01*
X606117Y-179426D01*
X607864Y-178843D01*
X609392Y-177093D01*
X610484Y-174468D01*
X610921Y-171843D01*
Y-168635D01*
X610484Y-166010D01*
X609392Y-163676D01*
X608082Y-162509D01*
X606554Y-161926D01*
X604807Y-162509D01*
X603497Y-163676D01*
X602624Y-165426D01*
X602187Y-167760D01*
X602624Y-169801D01*
X603716Y-171843D01*
X605026Y-173010D01*
X606554Y-173301D01*
X608300Y-172718D01*
X609611Y-171259D01*
X610921Y-168635D01*
G01X523437Y-134426D02*
Y-116926D01*
X528677D01*
X530424Y-117801D01*
X531734Y-119843D01*
X532171Y-122176D01*
X531734Y-124509D01*
X530642Y-126259D01*
X528677Y-127135D01*
X523437D01*
G01X550107Y-118385D02*
X548797Y-117509D01*
X547269Y-116926D01*
X545522D01*
X543557Y-117801D01*
X542029Y-119259D01*
X540937Y-121010D01*
X540064Y-123926D01*
X539845Y-126551D01*
X540282Y-129176D01*
X540937Y-130926D01*
X542247Y-132676D01*
X543776Y-133843D01*
X545304Y-134426D01*
X546832D01*
X548361Y-133843D01*
X549671Y-132968D01*
X550763Y-131802D01*
G01X564550Y-125093D02*
X565424Y-124218D01*
X566079Y-122760D01*
X566516Y-120717D01*
X566079Y-118968D01*
X565206Y-117801D01*
X563677Y-116926D01*
X557782D01*
Y-134426D01*
X564987D01*
X566516Y-133260D01*
X567389Y-131509D01*
X567826Y-129468D01*
X567389Y-127426D01*
X566079Y-125676D01*
X564550Y-125093D01*
X557782D01*
G01X573754Y-140259D02*
X586854D01*
G01X592782Y-134426D02*
Y-116926D01*
X602826Y-134426D01*
Y-116926D01*
G01X615304Y-134426D02*
X613557Y-134134D01*
X612029Y-132968D01*
X610719Y-131218D01*
X609845Y-129176D01*
X609409Y-126843D01*
Y-124509D01*
X609845Y-122176D01*
X610719Y-120134D01*
X612029Y-118385D01*
X613557Y-117218D01*
X615304Y-116926D01*
X617050Y-117218D01*
X618579Y-118385D01*
X619889Y-120134D01*
X620763Y-122176D01*
X621199Y-124509D01*
Y-126843D01*
X620763Y-129176D01*
X619889Y-131218D01*
X618579Y-132968D01*
X617050Y-134134D01*
X615304Y-134426D01*
G01X689104Y-179426D02*
Y-161926D01*
X686484Y-165426D01*
G01Y-179426D02*
X691724D01*
G01X701145D02*
X706604Y-161926D01*
X712063Y-179426D01*
G01X710097Y-173301D02*
X703110D01*
G01X666145Y-116926D02*
X671604Y-134426D01*
X677063Y-116926D01*
G01X693471Y-134426D02*
X684737D01*
Y-116926D01*
X693471D01*
G01X689977Y-125384D02*
X684737D01*
G01X702237Y-134426D02*
Y-116926D01*
X707696D01*
X709442Y-117801D01*
X710534Y-118968D01*
X710971Y-121301D01*
X710534Y-123635D01*
X709224Y-125093D01*
X707696Y-125968D01*
X702237D01*
G01X707696D02*
X710971Y-134426D01*
G01X724104Y-135009D02*
X723667Y-134718D01*
Y-134134D01*
X724104Y-133843D01*
X724541Y-134134D01*
Y-134718D01*
X724104Y-135009D01*
G01X790937Y-116926D02*
Y-134426D01*
X799671D01*
G01X816734D02*
Y-122760D01*
G01Y-124801D02*
X815861Y-123635D01*
X814550Y-123051D01*
X813022Y-122760D01*
X811494Y-123343D01*
X810184Y-124509D01*
X809310Y-126259D01*
X808874Y-128593D01*
X809310Y-130926D01*
X810184Y-132676D01*
X811494Y-133843D01*
X813022Y-134426D01*
X814550Y-134134D01*
X815861Y-133260D01*
X816734Y-132093D01*
G01X825719Y-139676D02*
X827029Y-140259D01*
X828776Y-139676D01*
X829867Y-138510D01*
X830741Y-137051D01*
X832050Y-132385D01*
X834889Y-122760D01*
G01X827902D02*
X832050Y-132385D01*
G01X844529Y-126551D02*
X851516D01*
X850861Y-124509D01*
X849769Y-123343D01*
X848241Y-122760D01*
X846712Y-123051D01*
X845402Y-123926D01*
X844529Y-125968D01*
X844092Y-127718D01*
Y-129468D01*
X844529Y-131218D01*
X845621Y-132968D01*
X846931Y-134134D01*
X848459Y-134426D01*
X849987Y-133843D01*
X851516Y-132093D01*
G01X862247Y-134426D02*
Y-122760D01*
G01Y-125093D02*
X863339Y-123926D01*
X864431Y-123051D01*
X865959Y-122760D01*
X867050Y-123051D01*
X868361Y-123926D01*
G01X879529Y-132385D02*
X880621Y-133551D01*
X882149Y-134426D01*
X883459D01*
X884769Y-133843D01*
X885642Y-132968D01*
X886079Y-131802D01*
X885861Y-130051D01*
X884987Y-129176D01*
X881057Y-127426D01*
X880184Y-125384D01*
X880621Y-123926D01*
X881494Y-123051D01*
X882804Y-122760D01*
X884114Y-123051D01*
X885424Y-123926D01*
G01X852171Y-161926D02*
Y-179426D01*
X843437D01*
G01X827684D02*
Y-161926D01*
X835763Y-174468D01*
X824845D01*
G01X924737Y-175926D02*
X925829Y-177676D01*
X927139Y-178843D01*
X928667Y-179426D01*
X930414Y-178843D01*
X931724Y-177676D01*
X933034Y-175926D01*
X933471Y-173593D01*
Y-161926D01*
G01X946604Y-179426D02*
X944857Y-179134D01*
X943329Y-177968D01*
X942019Y-176218D01*
X941145Y-174176D01*
X940709Y-171843D01*
Y-169509D01*
X941145Y-167176D01*
X942019Y-165134D01*
X943329Y-163385D01*
X944857Y-162218D01*
X946604Y-161926D01*
X948350Y-162218D01*
X949879Y-163385D01*
X951189Y-165134D01*
X952063Y-167176D01*
X952499Y-169509D01*
Y-171843D01*
X952063Y-174176D01*
X951189Y-176218D01*
X949879Y-177968D01*
X948350Y-179134D01*
X946604Y-179426D01*
G01X959519Y-177093D02*
X961266Y-178551D01*
X963231Y-179426D01*
X964977D01*
X966724Y-178551D01*
X968034Y-177093D01*
X968689Y-175051D01*
X968252Y-173010D01*
X967161Y-171259D01*
X965196Y-170093D01*
X962576Y-169509D01*
X961047Y-168343D01*
X960392Y-166301D01*
X960829Y-164259D01*
X961921Y-162801D01*
X963449Y-161926D01*
X964977D01*
X966506Y-162509D01*
X967816Y-163968D01*
G01X985971Y-179426D02*
X977237D01*
Y-161926D01*
X985971D01*
G01X982477Y-170384D02*
X977237D01*
G01X994737Y-179426D02*
Y-161926D01*
X999977D01*
X1001724Y-162801D01*
X1003034Y-164843D01*
X1003471Y-167176D01*
X1003034Y-169509D01*
X1001942Y-171259D01*
X999977Y-172135D01*
X994737D01*
G01X1012019Y-179426D02*
Y-161926D01*
G01X1021189D02*
Y-179426D01*
G01Y-170676D02*
X1012019D01*
G01X1047237Y-161926D02*
Y-179426D01*
X1055971D01*
G01X1063645D02*
X1069104Y-161926D01*
X1074563Y-179426D01*
G01X1072597Y-173301D02*
X1065610D01*
G01X1081801Y-161926D02*
Y-174468D01*
X1082674Y-177093D01*
X1084421Y-178843D01*
X1086604Y-179426D01*
X1088787Y-178843D01*
X1090534Y-177093D01*
X1091407Y-174468D01*
Y-161926D01*
G01X941801Y-134426D02*
Y-116926D01*
X946167D01*
X947914Y-117801D01*
X949224Y-118968D01*
X950316Y-120717D01*
X951189Y-122760D01*
X951407Y-125676D01*
X951189Y-128593D01*
X950316Y-130635D01*
X949224Y-132385D01*
X947914Y-133551D01*
X946167Y-134426D01*
X941801D01*
G01X960829Y-126551D02*
X967816D01*
X967161Y-124509D01*
X966069Y-123343D01*
X964541Y-122760D01*
X963012Y-123051D01*
X961702Y-123926D01*
X960829Y-125968D01*
X960392Y-127718D01*
Y-129468D01*
X960829Y-131218D01*
X961921Y-132968D01*
X963231Y-134134D01*
X964759Y-134426D01*
X966287Y-133843D01*
X967816Y-132093D01*
G01X978329Y-132385D02*
X979421Y-133551D01*
X980949Y-134426D01*
X982259D01*
X983569Y-133843D01*
X984442Y-132968D01*
X984879Y-131802D01*
X984661Y-130051D01*
X983787Y-129176D01*
X979857Y-127426D01*
X978984Y-125384D01*
X979421Y-123926D01*
X980294Y-123051D01*
X981604Y-122760D01*
X982914Y-123051D01*
X984224Y-123926D01*
G01X999104Y-122760D02*
Y-134426D01*
G01Y-118093D02*
X998667Y-117801D01*
Y-117218D01*
X999104Y-116926D01*
X999541Y-117218D01*
Y-117801D01*
X999104Y-118093D01*
G01X1013547Y-138801D02*
X1015076Y-139968D01*
X1016822Y-140259D01*
X1018350Y-139968D01*
X1019661Y-138510D01*
X1020534Y-136468D01*
Y-122760D01*
G01Y-125093D02*
X1019661Y-123926D01*
X1018350Y-123051D01*
X1016822Y-122760D01*
X1015076Y-123343D01*
X1013984Y-124509D01*
X1013110Y-126551D01*
X1012674Y-128593D01*
X1012892Y-130343D01*
X1013766Y-132385D01*
X1015076Y-133843D01*
X1016822Y-134426D01*
X1018132Y-134134D01*
X1019661Y-132968D01*
X1020534Y-131802D01*
G01X1030392Y-134426D02*
Y-122760D01*
G01Y-125676D02*
X1031266Y-124218D01*
X1032576Y-123051D01*
X1034322Y-122760D01*
X1035850Y-123051D01*
X1037161Y-124218D01*
X1037816Y-126259D01*
Y-134426D01*
G01X1048329Y-126551D02*
X1055316D01*
X1054661Y-124509D01*
X1053569Y-123343D01*
X1052041Y-122760D01*
X1050512Y-123051D01*
X1049202Y-123926D01*
X1048329Y-125968D01*
X1047892Y-127718D01*
Y-129468D01*
X1048329Y-131218D01*
X1049421Y-132968D01*
X1050731Y-134134D01*
X1052259Y-134426D01*
X1053787Y-133843D01*
X1055316Y-132093D01*
G01X1066047Y-134426D02*
Y-122760D01*
G01Y-125093D02*
X1067139Y-123926D01*
X1068231Y-123051D01*
X1069759Y-122760D01*
X1070850Y-123051D01*
X1072161Y-123926D01*
G01X1112804Y-179426D02*
Y-161926D01*
X1110184Y-165426D01*
G01Y-179426D02*
X1115424D01*
G01X1130304D02*
Y-161926D01*
X1127684Y-165426D01*
G01Y-179426D02*
X1132924D01*
G01X1143874Y-180009D02*
X1151734Y-161926D01*
G01X1161156Y-164843D02*
X1162466Y-163093D01*
X1163994Y-162218D01*
X1165741Y-161926D01*
X1167924Y-162509D01*
X1169452Y-163968D01*
X1169889Y-165717D01*
X1169671Y-167468D01*
X1168797Y-168926D01*
X1164431Y-171843D01*
X1162466Y-173884D01*
X1161156Y-176802D01*
X1160719Y-179426D01*
X1169889D01*
G01X1178001Y-176802D02*
X1179310Y-178260D01*
X1180839Y-179134D01*
X1182804Y-179426D01*
X1184769Y-178843D01*
X1186297Y-177676D01*
X1187389Y-175635D01*
X1187607Y-173301D01*
X1187171Y-170968D01*
X1186079Y-169509D01*
X1184550Y-168343D01*
X1183022Y-168051D01*
X1181494Y-168343D01*
X1179529Y-169509D01*
X1180184Y-161926D01*
X1186079D01*
G01X1196374Y-180009D02*
X1204234Y-161926D01*
G01X1213656Y-164843D02*
X1214966Y-163093D01*
X1216494Y-162218D01*
X1218241Y-161926D01*
X1220424Y-162509D01*
X1221952Y-163968D01*
X1222389Y-165717D01*
X1222171Y-167468D01*
X1221297Y-168926D01*
X1216931Y-171843D01*
X1214966Y-173884D01*
X1213656Y-176802D01*
X1213219Y-179426D01*
X1222389D01*
G01X1235304Y-161926D02*
X1233557Y-162509D01*
X1232247Y-163968D01*
X1231374Y-165717D01*
X1230719Y-168051D01*
X1230501Y-170676D01*
X1230719Y-173301D01*
X1231374Y-175635D01*
X1232247Y-177385D01*
X1233557Y-178843D01*
X1235304Y-179426D01*
X1237050Y-178843D01*
X1238361Y-177385D01*
X1239234Y-175635D01*
X1239889Y-173301D01*
X1240107Y-170676D01*
X1239889Y-168051D01*
X1239234Y-165717D01*
X1238361Y-163968D01*
X1237050Y-162509D01*
X1235304Y-161926D01*
G01X1252804Y-179426D02*
Y-161926D01*
X1250184Y-165426D01*
G01Y-179426D02*
X1255424D01*
G01X1272924D02*
Y-161926D01*
X1264845Y-174468D01*
X1275763D01*
G01X1160501Y-134426D02*
Y-116926D01*
X1164867D01*
X1166614Y-117801D01*
X1167924Y-118968D01*
X1169016Y-120717D01*
X1169889Y-122760D01*
X1170107Y-125676D01*
X1169889Y-128593D01*
X1169016Y-130635D01*
X1167924Y-132385D01*
X1166614Y-133551D01*
X1164867Y-134426D01*
X1160501D01*
G01X1186734D02*
Y-122760D01*
G01Y-124801D02*
X1185861Y-123635D01*
X1184550Y-123051D01*
X1183022Y-122760D01*
X1181494Y-123343D01*
X1180184Y-124509D01*
X1179310Y-126259D01*
X1178874Y-128593D01*
X1179310Y-130926D01*
X1180184Y-132676D01*
X1181494Y-133843D01*
X1183022Y-134426D01*
X1184550Y-134134D01*
X1185861Y-133260D01*
X1186734Y-132093D01*
G01X1200304Y-116926D02*
Y-134426D01*
G01X1197247Y-122760D02*
X1203361D01*
G01X1214529Y-126551D02*
X1221516D01*
X1220861Y-124509D01*
X1219769Y-123343D01*
X1218241Y-122760D01*
X1216712Y-123051D01*
X1215402Y-123926D01*
X1214529Y-125968D01*
X1214092Y-127718D01*
Y-129468D01*
X1214529Y-131218D01*
X1215621Y-132968D01*
X1216931Y-134134D01*
X1218459Y-134426D01*
X1219987Y-133843D01*
X1221516Y-132093D01*
G54D14*
X-22005Y124122D03*
Y133422D03*
Y142722D03*
Y164122D03*
Y173422D03*
Y182722D03*
Y204122D03*
Y213422D03*
Y222722D03*
Y244122D03*
Y253422D03*
Y262722D03*
Y283072D03*
G54D24*
G01X3398Y326936D02*
X500D01*
X-6936Y319500D01*
X-14609D01*
X-16907Y317202D01*
X-26055D01*
G01Y322202D02*
X-8000D01*
X-702Y329500D01*
X19000D01*
X19936Y330436D01*
X26500D01*
G01X10000Y332000D02*
X-3952D01*
X-5500Y330452D01*
X-12392D01*
X-15642Y327202D01*
X-26055D01*
G01X1494Y343705D02*
X-1211Y341000D01*
X-2722D01*
G01X5694Y343705D02*
X1635Y347764D01*
G01X-26055Y332202D02*
X-6336D01*
X-2538Y336000D01*
X14000D01*
G01X-26055Y342202D02*
X-12500D01*
X-11298Y341000D01*
X-2722D01*
G01X-26055Y352202D02*
X-2803D01*
X1635Y347764D01*
G01X30923Y335665D02*
Y332169D01*
X29190Y330436D01*
X26500D01*
G01X26723Y335665D02*
X26388Y336000D01*
X14000D01*
G01X487039Y340243D02*
X550000Y277282D01*
Y221000D01*
X562500Y208500D01*
X576618D01*
X580709Y204409D01*
G01Y214409D02*
X576584Y210284D01*
X563239D01*
X551784Y221739D01*
Y277973D01*
X489500Y340257D01*
Y352200D01*
G01D02*
Y375500D01*
G01X485500D02*
X487039Y373961D01*
Y340243D01*
G01X580709Y244409D02*
X576300Y240000D01*
X565500D01*
X557000Y231500D01*
G01X580709Y234409D02*
X576868Y238250D01*
X566250D01*
X561500Y233500D01*
Y232000D01*
G54D15*
X-25005Y133422D03*
Y173422D03*
Y213422D03*
Y253422D03*
G54D16*
X-27555Y302202D03*
Y307202D03*
Y312202D03*
Y317202D03*
Y322202D03*
Y327202D03*
Y332202D03*
Y337202D03*
Y342202D03*
Y347202D03*
Y352202D03*
Y357202D03*
G54D17*
X-25005Y283072D03*
G54D18*
X570709Y161889D03*
X580709D03*
X570709Y214409D03*
X580709D03*
X570709Y204409D03*
X580709D03*
X570709Y191889D03*
X580709D03*
X570709Y181889D03*
X580709D03*
X570709Y171889D03*
X580709D03*
X570709Y244409D03*
X580709D03*
X570709Y276929D03*
X580709D03*
X570709Y266929D03*
X580709D03*
X570709Y256929D03*
X580709D03*
X570709Y234409D03*
X580709D03*
X570709Y224409D03*
X580709D03*
X570709Y286929D03*
X580709D03*
X590709Y161889D03*
X600709D03*
X590709Y214409D03*
X600709D03*
X590709Y204409D03*
X600709D03*
X590709Y191889D03*
X600709D03*
X590709Y181889D03*
X600709D03*
X590709Y171889D03*
X600709D03*
X590709Y244409D03*
X600709D03*
X590709Y276929D03*
X600709D03*
X590709Y266929D03*
X600709D03*
X590709Y256929D03*
X600709D03*
X590709Y234409D03*
X600709D03*
X590709Y224409D03*
X600709D03*
X590709Y286929D03*
X600709D03*
G54D19*
X559489Y427559D03*
X603780Y442126D03*
M02*
